# T6G (Grand Teton) — schematic netlist excerpt (pin names and nets, part order shuffled) for the footprints in the layout excerpt that follows; sources: Cadence DE-HDL packaged netlist, KiCad conversion of 04192023_DAF0TMB3IC0_F0TG_MB_C_brd_V02_OCP.brd

R9446  Q_RES  33.2 1% CHIP  pkg 0402LF  page 253 : A = PWRGD_PS_PWROK_PLD_ISO ; B = PWRGD_PS_PWROK_PLD_ISO_R
C6676  Q_CAP_DIFFBUS  DIFF BUS_0.22UF 6.3V 20% X6S  pkg C0201  page 330 : \1\ = P5E_CPU1_P1_TX_BUF_C_DN<7> ; \2\ = P5E_CPU1_P1_TX_BUF_DN<7>
C397  Q_CAP  0.1UF 10V 10% X7S  pkg C0201  page 345 : A = P0V9_CPU1_RT2_2A_2D ; B = GND
R709  Q_RES  0 5% CHIP  pkg 0201LF  page 321 : A = NCF_CPU1_P0_GND ; B = GND

(kicad_pcb
	(version 20260206)
	(generator "pcbnew")
	(generator_version "10.0")
	(general
		(thickness 1.6)
		(legacy_teardrops no)
	)
	(paper "A4")
	(title_block
		(title "04192023_DAF0TMB3IC0_F0TG_MB_C_brd_V02_OCP.brd")
		(comment 1 "Grand Teton / footprints 7793-7796 of 8354")
	)
	(layers
		(0 "F.Cu" signal "TOP")
		(4 "In1.Cu" signal "GND")
		(6 "In2.Cu" signal "IN1")
		(8 "In3.Cu" signal "GND1")
		(10 "In4.Cu" signal "IN2")
		(12 "In5.Cu" signal "GND2")
		(14 "In6.Cu" signal "IN3")
		(16 "In7.Cu" signal "GND3")
		(18 "In8.Cu" signal "VCC")
		(20 "In9.Cu" signal "VCC1")
		(22 "In10.Cu" signal "GND4")
		(24 "In11.Cu" signal "IN4")
		(26 "In12.Cu" signal "GND5")
		(28 "In13.Cu" signal "IN5")
		(30 "In14.Cu" signal "GND6")
		(32 "In15.Cu" signal "IN6")
		(34 "In16.Cu" signal "GND7")
		(2 "B.Cu" signal "BOTTOM")
		(9 "F.Adhes" user "F.Adhesive")
		(11 "B.Adhes" user "B.Adhesive")
		(13 "F.Paste" user "Package Geometry/Pastemask Top")
		(15 "B.Paste" user "Package Geometry/Pastemask Bottom")
		(5 "F.SilkS" user "Ref Des/Silkscreen Top")
		(7 "B.SilkS" user "Ref Des/Silkscreen Bottom")
		(1 "F.Mask" user "Board Geometry/Soldermask Top")
		(3 "B.Mask" user "Board Geometry/Soldermask Bottom")
		(17 "Dwgs.User" user "User.Drawings")
		(19 "Cmts.User" user "User.Comments")
		(21 "Eco1.User" user "User.Eco1")
		(23 "Eco2.User" user "User.Eco2")
		(25 "Edge.Cuts" user "Board Geometry/Outline")
		(27 "Margin" user)
		(31 "F.CrtYd" user "Package Geometry/Place Bound Top")
		(29 "B.CrtYd" user "Package Geometry/Place Bound Bottom")
		(35 "F.Fab" user "Ref Des/Assembly Top")
		(33 "B.Fab" user "Ref Des/Assembly Bottom")
	)
	(footprint ""
		(layer "B.Cu")
		(at 311.427876 -78.775814 -90)
		(property "Reference" "R9446"
			(at 0 0 90)
			(layer "B.SilkS")
			(hide yes)
			(effects
				(font
					(size 1.27 1.27)
				)
				(justify mirror)
			)
		)
		(property "Value" ""
			(at 0 0 90)
			(layer "B.Fab")
			(effects
				(font
					(size 1.27 1.27)
				)
				(justify mirror)
			)
		)
		(duplicate_pad_numbers_are_jumpers no)
		(fp_line
			(start -0.7874 0.4064)
			(end 0.7874 0.4064)
			(stroke
				(width 0.1524)
				(type default)
			)
			(layer "B.SilkS")
		)
		(fp_line
			(start 0.7874 0.4064)
			(end 0.7874 -0.4064)
			(stroke
				(width 0.1524)
				(type default)
			)
			(layer "B.SilkS")
		)
		(fp_line
			(start -0.7874 -0.4064)
			(end -0.7874 0.4064)
			(stroke
				(width 0.1524)
				(type default)
			)
			(layer "B.SilkS")
		)
		(fp_line
			(start 0.7874 -0.4064)
			(end -0.7874 -0.4064)
			(stroke
				(width 0.1524)
				(type default)
			)
			(layer "B.SilkS")
		)
		(fp_line
			(start -0.67945 0.3048)
			(end -0.120396 0.3048)
			(stroke
				(width 0.1)
				(type default)
			)
			(layer "B.Fab")
		)
		(fp_line
			(start -0.120396 0.3048)
			(end -0.120396 0.2794)
			(stroke
				(width 0.1)
				(type default)
			)
			(layer "B.Fab")
		)
		(fp_line
			(start 0.12065 0.3048)
			(end 0.67945 0.3048)
			(stroke
				(width 0.1)
				(type default)
			)
			(layer "B.Fab")
		)
		(fp_line
			(start 0.67945 0.3048)
			(end 0.67945 -0.305054)
			(stroke
				(width 0.1)
				(type default)
			)
			(layer "B.Fab")
		)
		(fp_line
			(start -0.120396 0.2794)
			(end 0.12065 0.2794)
			(stroke
				(width 0.1)
				(type default)
			)
			(layer "B.Fab")
		)
		(fp_line
			(start 0.12065 0.2794)
			(end 0.12065 0.3048)
			(stroke
				(width 0.1)
				(type default)
			)
			(layer "B.Fab")
		)
		(fp_line
			(start -0.12065 -0.2794)
			(end -0.12065 -0.3048)
			(stroke
				(width 0.1)
				(type default)
			)
			(layer "B.Fab")
		)
		(fp_line
			(start 0.12065 -0.2794)
			(end -0.12065 -0.2794)
			(stroke
				(width 0.1)
				(type default)
			)
			(layer "B.Fab")
		)
		(fp_line
			(start -0.67945 -0.3048)
			(end -0.67945 0.3048)
			(stroke
				(width 0.1)
				(type default)
			)
			(layer "B.Fab")
		)
		(fp_line
			(start -0.12065 -0.3048)
			(end -0.67945 -0.3048)
			(stroke
				(width 0.1)
				(type default)
			)
			(layer "B.Fab")
		)
		(fp_line
			(start 0.12065 -0.305054)
			(end 0.12065 -0.2794)
			(stroke
				(width 0.1)
				(type default)
			)
			(layer "B.Fab")
		)
		(fp_line
			(start 0.67945 -0.305054)
			(end 0.12065 -0.305054)
			(stroke
				(width 0.1)
				(type default)
			)
			(layer "B.Fab")
		)
		(pad "1" smd circle
			(at 0.40005 0 90)
			(size 0 0)
			(layers "B.Cu" "B.Mask" "B.Paste")
			(net "PWRGD_PS_PWROK_PLD_ISO")
		)
		(pad "2" smd circle
			(at -0.40005 0 90)
			(size 0 0)
			(layers "B.Cu" "B.Mask" "B.Paste")
			(net "PWRGD_PS_PWROK_PLD_ISO_R")
		)
	)
	(footprint ""
		(layer "B.Cu")
		(at 70.743064 -408.517344 90)
		(property "Reference" "C6676"
			(at 0 0 90)
			(layer "B.SilkS")
			(hide yes)
			(effects
				(font
					(size 1.27 1.27)
				)
				(justify mirror)
			)
		)
		(property "Value" ""
			(at 0 0 90)
			(layer "B.Fab")
			(effects
				(font
					(size 1.27 1.27)
				)
				(justify mirror)
			)
		)
		(duplicate_pad_numbers_are_jumpers no)
		(fp_line
			(start 0.299974 -0.150114)
			(end -0.299974 -0.150114)
			(stroke
				(width 0.1)
				(type default)
			)
			(layer "B.Fab")
		)
		(fp_line
			(start -0.299974 -0.150114)
			(end -0.299974 0.150114)
			(stroke
				(width 0.1)
				(type default)
			)
			(layer "B.Fab")
		)
		(fp_line
			(start 0.299974 0.150114)
			(end 0.299974 -0.150114)
			(stroke
				(width 0.1)
				(type default)
			)
			(layer "B.Fab")
		)
		(fp_line
			(start -0.299974 0.150114)
			(end 0.299974 0.150114)
			(stroke
				(width 0.1)
				(type default)
			)
			(layer "B.Fab")
		)
		(pad "1" smd rect
			(at 0.2667 0 270)
			(size 0.3048 0.381)
			(layers "B.Cu" "B.Mask" "B.Paste")
			(net "P5E_CPU1_P1_TX_BUF_C_DN<7>")
		)
		(pad "2" smd rect
			(at -0.2667 0 270)
			(size 0.3048 0.381)
			(layers "B.Cu" "B.Mask" "B.Paste")
			(net "P5E_CPU1_P1_TX_BUF_DN<7>")
		)
	)
	(footprint ""
		(layer "B.Cu")
		(at 160.346136 -388.011162 -90)
		(property "Reference" "C397"
			(at 0 0 90)
			(layer "B.SilkS")
			(hide yes)
			(effects
				(font
					(size 1.27 1.27)
				)
				(justify mirror)
			)
		)
		(property "Value" ""
			(at 0 0 90)
			(layer "B.Fab")
			(effects
				(font
					(size 1.27 1.27)
				)
				(justify mirror)
			)
		)
		(duplicate_pad_numbers_are_jumpers no)
		(fp_line
			(start -0.299974 0.150114)
			(end 0.299974 0.150114)
			(stroke
				(width 0.1)
				(type default)
			)
			(layer "B.Fab")
		)
		(fp_line
			(start 0.299974 0.150114)
			(end 0.299974 -0.150114)
			(stroke
				(width 0.1)
				(type default)
			)
			(layer "B.Fab")
		)
		(fp_line
			(start -0.299974 -0.150114)
			(end -0.299974 0.150114)
			(stroke
				(width 0.1)
				(type default)
			)
			(layer "B.Fab")
		)
		(fp_line
			(start 0.299974 -0.150114)
			(end -0.299974 -0.150114)
			(stroke
				(width 0.1)
				(type default)
			)
			(layer "B.Fab")
		)
		(pad "1" smd rect
			(at 0.2667 0 90)
			(size 0.3048 0.381)
			(layers "B.Cu" "B.Mask" "B.Paste")
			(net "P0V9_CPU1_RT2_2A_2D")
		)
		(pad "2" smd rect
			(at -0.2667 0 90)
			(size 0.3048 0.381)
			(layers "B.Cu" "B.Mask" "B.Paste")
			(net "GND")
		)
	)
	(footprint ""
		(layer "B.Cu")
		(at 70.0532 -382.8796 180)
		(property "Reference" "R709"
			(at 0 0 0)
			(layer "B.SilkS")
			(hide yes)
			(effects
				(font
					(size 1.27 1.27)
				)
				(justify mirror)
			)
		)
		(property "Value" ""
			(at 0 0 0)
			(layer "B.Fab")
			(effects
				(font
					(size 1.27 1.27)
				)
				(justify mirror)
			)
		)
		(duplicate_pad_numbers_are_jumpers no)
		(fp_line
			(start 0.32512 0.175006)
			(end 0.32512 -0.175006)
			(stroke
				(width 0.1)
				(type default)
			)
			(layer "B.Fab")
		)
		(fp_line
			(start 0.32512 -0.175006)
			(end -0.32512 -0.175006)
			(stroke
				(width 0.1)
				(type default)
			)
			(layer "B.Fab")
		)
		(fp_line
			(start -0.32512 0.175006)
			(end 0.32512 0.175006)
			(stroke
				(width 0.1)
				(type default)
			)
			(layer "B.Fab")
		)
		(fp_line
			(start -0.32512 -0.175006)
			(end -0.32512 0.175006)
			(stroke
				(width 0.1)
				(type default)
			)
			(layer "B.Fab")
		)
		(pad "1" smd rect
			(at 0.2667 0)
			(size 0.3048 0.381)
			(layers "B.Cu" "B.Mask" "B.Paste")
			(net "NCF_CPU1_P0_GND")
		)
		(pad "2" smd rect
			(at -0.2667 0 180)
			(size 0.3048 0.381)
			(layers "B.Cu" "B.Mask" "B.Paste")
			(net "GND")
		)
	)
)
